# T6G (Grand Teton) — schematic netlist excerpt (pin names and nets, part order shuffled) for the footprints in the layout excerpt that follows; sources: Cadence DE-HDL packaged netlist, KiCad conversion of 04192023_DAF0TMB3IC0_F0TG_MB_C_brd_V02_OCP.brd

R329  Q_RES  2K 1% EMPTY  pkg 0402LF  page 151 : A = SMB_PMBUS_3V3AUX_SDA ; B = P3V3_AUX
C5011  Q_CAP  1000PF 50V 5% X7R  pkg 0402  page 193 : A = PVDDCR_CPU0_P0_PMALERT ; B = GND

(kicad_pcb
	(version 20260206)
	(generator "pcbnew")
	(generator_version "10.0")
	(general
		(thickness 1.6)
		(legacy_teardrops no)
	)
	(paper "A4")
	(title_block
		(title "04192023_DAF0TMB3IC0_F0TG_MB_C_brd_V02_OCP.brd")
		(comment 1 "Grand Teton / footprints 5425-5426 of 8354")
	)
	(layers
		(0 "F.Cu" signal "TOP")
		(4 "In1.Cu" signal "GND")
		(6 "In2.Cu" signal "IN1")
		(8 "In3.Cu" signal "GND1")
		(10 "In4.Cu" signal "IN2")
		(12 "In5.Cu" signal "GND2")
		(14 "In6.Cu" signal "IN3")
		(16 "In7.Cu" signal "GND3")
		(18 "In8.Cu" signal "VCC")
		(20 "In9.Cu" signal "VCC1")
		(22 "In10.Cu" signal "GND4")
		(24 "In11.Cu" signal "IN4")
		(26 "In12.Cu" signal "GND5")
		(28 "In13.Cu" signal "IN5")
		(30 "In14.Cu" signal "GND6")
		(32 "In15.Cu" signal "IN6")
		(34 "In16.Cu" signal "GND7")
		(2 "B.Cu" signal "BOTTOM")
		(9 "F.Adhes" user "F.Adhesive")
		(11 "B.Adhes" user "B.Adhesive")
		(13 "F.Paste" user "Package Geometry/Pastemask Top")
		(15 "B.Paste" user "Package Geometry/Pastemask Bottom")
		(5 "F.SilkS" user "Ref Des/Silkscreen Top")
		(7 "B.SilkS" user "Ref Des/Silkscreen Bottom")
		(1 "F.Mask" user "Board Geometry/Soldermask Top")
		(3 "B.Mask" user "Board Geometry/Soldermask Bottom")
		(17 "Dwgs.User" user "User.Drawings")
		(19 "Cmts.User" user "User.Comments")
		(21 "Eco1.User" user "User.Eco1")
		(23 "Eco2.User" user "User.Eco2")
		(25 "Edge.Cuts" user "Board Geometry/Outline")
		(27 "Margin" user)
		(31 "F.CrtYd" user "Package Geometry/Place Bound Top")
		(29 "B.CrtYd" user "Package Geometry/Place Bound Bottom")
		(35 "F.Fab" user "Ref Des/Assembly Top")
		(33 "B.Fab" user "Ref Des/Assembly Bottom")
	)
	(footprint ""
		(layer "B.Cu")
		(at 164.949378 -17.417288 180)
		(property "Reference" "R329"
			(at 0 0 0)
			(layer "B.SilkS")
			(hide yes)
			(effects
				(font
					(size 1.27 1.27)
				)
				(justify mirror)
			)
		)
		(property "Value" ""
			(at 0 0 0)
			(layer "B.Fab")
			(effects
				(font
					(size 1.27 1.27)
				)
				(justify mirror)
			)
		)
		(duplicate_pad_numbers_are_jumpers no)
		(fp_line
			(start 0.7874 0.4064)
			(end 0.7874 -0.4064)
			(stroke
				(width 0.1524)
				(type default)
			)
			(layer "B.SilkS")
		)
		(fp_line
			(start 0.7874 -0.4064)
			(end -0.7874 -0.4064)
			(stroke
				(width 0.1524)
				(type default)
			)
			(layer "B.SilkS")
		)
		(fp_line
			(start -0.7874 0.4064)
			(end 0.7874 0.4064)
			(stroke
				(width 0.1524)
				(type default)
			)
			(layer "B.SilkS")
		)
		(fp_line
			(start -0.7874 -0.4064)
			(end -0.7874 0.4064)
			(stroke
				(width 0.1524)
				(type default)
			)
			(layer "B.SilkS")
		)
		(fp_line
			(start 0.67945 0.3048)
			(end 0.67945 -0.305054)
			(stroke
				(width 0.1)
				(type default)
			)
			(layer "B.Fab")
		)
		(fp_line
			(start 0.67945 -0.305054)
			(end 0.12065 -0.305054)
			(stroke
				(width 0.1)
				(type default)
			)
			(layer "B.Fab")
		)
		(fp_line
			(start 0.12065 0.3048)
			(end 0.67945 0.3048)
			(stroke
				(width 0.1)
				(type default)
			)
			(layer "B.Fab")
		)
		(fp_line
			(start 0.12065 0.2794)
			(end 0.12065 0.3048)
			(stroke
				(width 0.1)
				(type default)
			)
			(layer "B.Fab")
		)
		(fp_line
			(start 0.12065 -0.2794)
			(end -0.12065 -0.2794)
			(stroke
				(width 0.1)
				(type default)
			)
			(layer "B.Fab")
		)
		(fp_line
			(start 0.12065 -0.305054)
			(end 0.12065 -0.2794)
			(stroke
				(width 0.1)
				(type default)
			)
			(layer "B.Fab")
		)
		(fp_line
			(start -0.120396 0.3048)
			(end -0.120396 0.2794)
			(stroke
				(width 0.1)
				(type default)
			)
			(layer "B.Fab")
		)
		(fp_line
			(start -0.120396 0.2794)
			(end 0.12065 0.2794)
			(stroke
				(width 0.1)
				(type default)
			)
			(layer "B.Fab")
		)
		(fp_line
			(start -0.12065 -0.2794)
			(end -0.12065 -0.3048)
			(stroke
				(width 0.1)
				(type default)
			)
			(layer "B.Fab")
		)
		(fp_line
			(start -0.12065 -0.3048)
			(end -0.67945 -0.3048)
			(stroke
				(width 0.1)
				(type default)
			)
			(layer "B.Fab")
		)
		(fp_line
			(start -0.67945 0.3048)
			(end -0.120396 0.3048)
			(stroke
				(width 0.1)
				(type default)
			)
			(layer "B.Fab")
		)
		(fp_line
			(start -0.67945 -0.3048)
			(end -0.67945 0.3048)
			(stroke
				(width 0.1)
				(type default)
			)
			(layer "B.Fab")
		)
		(pad "1" smd circle
			(at 0.40005 0)
			(size 0 0)
			(layers "B.Cu" "B.Mask" "B.Paste")
			(net "SMB_PMBUS_3V3AUX_SDA")
		)
		(pad "2" smd circle
			(at -0.40005 0)
			(size 0 0)
			(layers "B.Cu" "B.Mask" "B.Paste")
			(net "P3V3_AUX")
		)
	)
	(footprint ""
		(layer "B.Cu")
		(at 372.321328 -137.008108 90)
		(property "Reference" "C5011"
			(at 0 0 90)
			(layer "B.SilkS")
			(hide yes)
			(effects
				(font
					(size 1.27 1.27)
				)
				(justify mirror)
			)
		)
		(property "Value" ""
			(at 0 0 90)
			(layer "B.Fab")
			(effects
				(font
					(size 1.27 1.27)
				)
				(justify mirror)
			)
		)
		(duplicate_pad_numbers_are_jumpers no)
		(fp_line
			(start 0.7874 -0.4064)
			(end -0.7874 -0.4064)
			(stroke
				(width 0.1524)
				(type default)
			)
			(layer "B.SilkS")
		)
		(fp_line
			(start -0.7874 -0.4064)
			(end -0.7874 0.4064)
			(stroke
				(width 0.1524)
				(type default)
			)
			(layer "B.SilkS")
		)
		(fp_line
			(start 0.7874 0.4064)
			(end 0.7874 -0.4064)
			(stroke
				(width 0.1524)
				(type default)
			)
			(layer "B.SilkS")
		)
		(fp_line
			(start -0.7874 0.4064)
			(end 0.7874 0.4064)
			(stroke
				(width 0.1524)
				(type default)
			)
			(layer "B.SilkS")
		)
		(fp_line
			(start 0.67945 -0.305054)
			(end 0.12065 -0.305054)
			(stroke
				(width 0.1)
				(type default)
			)
			(layer "B.Fab")
		)
		(fp_line
			(start 0.12065 -0.305054)
			(end 0.12065 -0.2794)
			(stroke
				(width 0.1)
				(type default)
			)
			(layer "B.Fab")
		)
		(fp_line
			(start -0.12065 -0.3048)
			(end -0.67945 -0.3048)
			(stroke
				(width 0.1)
				(type default)
			)
			(layer "B.Fab")
		)
		(fp_line
			(start -0.67945 -0.3048)
			(end -0.67945 0.3048)
			(stroke
				(width 0.1)
				(type default)
			)
			(layer "B.Fab")
		)
		(fp_line
			(start 0.12065 -0.2794)
			(end -0.12065 -0.2794)
			(stroke
				(width 0.1)
				(type default)
			)
			(layer "B.Fab")
		)
		(fp_line
			(start -0.12065 -0.2794)
			(end -0.12065 -0.3048)
			(stroke
				(width 0.1)
				(type default)
			)
			(layer "B.Fab")
		)
		(fp_line
			(start 0.12065 0.2794)
			(end 0.12065 0.3048)
			(stroke
				(width 0.1)
				(type default)
			)
			(layer "B.Fab")
		)
		(fp_line
			(start -0.120396 0.2794)
			(end 0.12065 0.2794)
			(stroke
				(width 0.1)
				(type default)
			)
			(layer "B.Fab")
		)
		(fp_line
			(start 0.67945 0.3048)
			(end 0.67945 -0.305054)
			(stroke
				(width 0.1)
				(type default)
			)
			(layer "B.Fab")
		)
		(fp_line
			(start 0.12065 0.3048)
			(end 0.67945 0.3048)
			(stroke
				(width 0.1)
				(type default)
			)
			(layer "B.Fab")
		)
		(fp_line
			(start -0.120396 0.3048)
			(end -0.120396 0.2794)
			(stroke
				(width 0.1)
				(type default)
			)
			(layer "B.Fab")
		)
		(fp_line
			(start -0.67945 0.3048)
			(end -0.120396 0.3048)
			(stroke
				(width 0.1)
				(type default)
			)
			(layer "B.Fab")
		)
		(pad "1" smd circle
			(at 0.40005 0 270)
			(size 0 0)
			(layers "B.Cu" "B.Mask" "B.Paste")
			(net "PVDDCR_CPU0_P0_PMALERT")
		)
		(pad "2" smd circle
			(at -0.40005 0 270)
			(size 0 0)
			(layers "B.Cu" "B.Mask" "B.Paste")
			(net "GND")
		)
	)
)
